# S9S_MB_2U (Grand Teton) — schematic netlist excerpt (pin names and nets, part order shuffled) for the footprints in the layout excerpt that follows; sources: Cadence DE-HDL packaged netlist, KiCad conversion of 03242023_DA0F0TMBIJ0_F0T_Motherboard_J_brd_V01_OCP.brd

C86  Q_CAP  10UF 16V 10% X6S  pkg C0805  page 109 : A = P12V_S3_AUX_CPU1_NVDIMM ; B = GND
R842  Q_RES  1K 1% CHIP  pkg 0402LF  page 129 : A = PVCCD_HV_CPU0 ; B = RST_M_EF_CPU0_FPGA_N
R62  Q_RES  100 1% CHIP  pkg 0402LF  page 44 : A = H_CPU_PREQ_QS_GTL_N ; B = H_CPU1_PREQ_QS_GTL_R_N

(kicad_pcb
	(version 20260206)
	(generator "pcbnew")
	(generator_version "10.0")
	(general
		(thickness 1.6)
		(legacy_teardrops no)
	)
	(paper "A4")
	(title_block
		(title "03242023_DA0F0TMBIJ0_F0T_Motherboard_J_brd_V01_OCP.brd")
		(comment 1 "Grand Teton / footprints 4310-4312 of 6105")
	)
	(layers
		(0 "F.Cu" signal "TOP")
		(4 "In1.Cu" signal "GND")
		(6 "In2.Cu" signal "IN1")
		(8 "In3.Cu" signal "GND1")
		(10 "In4.Cu" signal "IN2")
		(12 "In5.Cu" signal "GND2")
		(14 "In6.Cu" signal "IN3")
		(16 "In7.Cu" signal "GND3")
		(18 "In8.Cu" signal "VCC")
		(20 "In9.Cu" signal "VCC1")
		(22 "In10.Cu" signal "GND4")
		(24 "In11.Cu" signal "IN4")
		(26 "In12.Cu" signal "GND5")
		(28 "In13.Cu" signal "IN5")
		(30 "In14.Cu" signal "GND6")
		(32 "In15.Cu" signal "IN6")
		(34 "In16.Cu" signal "GND7")
		(2 "B.Cu" signal "BOTTOM")
		(9 "F.Adhes" user "F.Adhesive")
		(11 "B.Adhes" user "B.Adhesive")
		(13 "F.Paste" user "Package Geometry/Pastemask Top")
		(15 "B.Paste" user "Package Geometry/Pastemask Bottom")
		(5 "F.SilkS" user "Ref Des/Silkscreen Top")
		(7 "B.SilkS" user "Ref Des/Silkscreen Bottom")
		(1 "F.Mask" user "Board Geometry/Soldermask Top")
		(3 "B.Mask" user "Board Geometry/Soldermask Bottom")
		(17 "Dwgs.User" user "User.Drawings")
		(19 "Cmts.User" user "User.Comments")
		(21 "Eco1.User" user "User.Eco1")
		(23 "Eco2.User" user "User.Eco2")
		(25 "Edge.Cuts" user "Board Geometry/Outline")
		(27 "Margin" user)
		(31 "F.CrtYd" user "Package Geometry/Place Bound Top")
		(29 "B.CrtYd" user "Package Geometry/Place Bound Bottom")
		(35 "F.Fab" user "Ref Des/Assembly Top")
		(33 "B.Fab" user "Ref Des/Assembly Bottom")
	)
	(footprint ""
		(layer "B.Cu")
		(at 76.463652 -183.470296 -90)
		(property "Reference" "R62"
			(at 0 0 90)
			(layer "B.SilkS")
			(hide yes)
			(effects
				(font
					(size 1.27 1.27)
				)
				(justify mirror)
			)
		)
		(property "Value" ""
			(at 0 0 90)
			(layer "B.Fab")
			(effects
				(font
					(size 1.27 1.27)
				)
				(justify mirror)
			)
		)
		(duplicate_pad_numbers_are_jumpers no)
		(fp_line
			(start -0.7874 0.4064)
			(end 0.7874 0.4064)
			(stroke
				(width 0.1524)
				(type default)
			)
			(layer "B.SilkS")
		)
		(fp_line
			(start 0.7874 0.4064)
			(end 0.7874 -0.4064)
			(stroke
				(width 0.1524)
				(type default)
			)
			(layer "B.SilkS")
		)
		(fp_line
			(start -0.7874 -0.4064)
			(end -0.7874 0.4064)
			(stroke
				(width 0.1524)
				(type default)
			)
			(layer "B.SilkS")
		)
		(fp_line
			(start 0.7874 -0.4064)
			(end -0.7874 -0.4064)
			(stroke
				(width 0.1524)
				(type default)
			)
			(layer "B.SilkS")
		)
		(fp_line
			(start -0.67945 0.3048)
			(end -0.120396 0.3048)
			(stroke
				(width 0.1)
				(type default)
			)
			(layer "B.Fab")
		)
		(fp_line
			(start -0.120396 0.3048)
			(end -0.120396 0.2794)
			(stroke
				(width 0.1)
				(type default)
			)
			(layer "B.Fab")
		)
		(fp_line
			(start 0.12065 0.3048)
			(end 0.67945 0.3048)
			(stroke
				(width 0.1)
				(type default)
			)
			(layer "B.Fab")
		)
		(fp_line
			(start 0.67945 0.3048)
			(end 0.67945 -0.305054)
			(stroke
				(width 0.1)
				(type default)
			)
			(layer "B.Fab")
		)
		(fp_line
			(start -0.120396 0.2794)
			(end 0.12065 0.2794)
			(stroke
				(width 0.1)
				(type default)
			)
			(layer "B.Fab")
		)
		(fp_line
			(start 0.12065 0.2794)
			(end 0.12065 0.3048)
			(stroke
				(width 0.1)
				(type default)
			)
			(layer "B.Fab")
		)
		(fp_line
			(start -0.12065 -0.2794)
			(end -0.12065 -0.3048)
			(stroke
				(width 0.1)
				(type default)
			)
			(layer "B.Fab")
		)
		(fp_line
			(start 0.12065 -0.2794)
			(end -0.12065 -0.2794)
			(stroke
				(width 0.1)
				(type default)
			)
			(layer "B.Fab")
		)
		(fp_line
			(start -0.67945 -0.3048)
			(end -0.67945 0.3048)
			(stroke
				(width 0.1)
				(type default)
			)
			(layer "B.Fab")
		)
		(fp_line
			(start -0.12065 -0.3048)
			(end -0.67945 -0.3048)
			(stroke
				(width 0.1)
				(type default)
			)
			(layer "B.Fab")
		)
		(fp_line
			(start 0.12065 -0.305054)
			(end 0.12065 -0.2794)
			(stroke
				(width 0.1)
				(type default)
			)
			(layer "B.Fab")
		)
		(fp_line
			(start 0.67945 -0.305054)
			(end 0.12065 -0.305054)
			(stroke
				(width 0.1)
				(type default)
			)
			(layer "B.Fab")
		)
		(pad "1" smd circle
			(at 0.40005 0 90)
			(size 0 0)
			(layers "B.Cu" "B.Mask" "B.Paste")
			(net "H_CPU_PREQ_QS_GTL_N")
		)
		(pad "2" smd circle
			(at -0.40005 0 90)
			(size 0 0)
			(layers "B.Cu" "B.Mask" "B.Paste")
			(net "H_CPU1_PREQ_QS_GTL_R_N")
		)
	)
	(footprint ""
		(layer "B.Cu")
		(at 173.913546 -321.554856 -90)
		(property "Reference" "C86"
			(at 0 0 90)
			(layer "B.SilkS")
			(hide yes)
			(effects
				(font
					(size 1.27 1.27)
				)
				(justify mirror)
			)
		)
		(property "Value" ""
			(at 0 0 90)
			(layer "B.Fab")
			(effects
				(font
					(size 1.27 1.27)
				)
				(justify mirror)
			)
		)
		(duplicate_pad_numbers_are_jumpers no)
		(fp_line
			(start -1.524 0.762)
			(end 1.524 0.762)
			(stroke
				(width 0.1524)
				(type default)
			)
			(layer "B.SilkS")
		)
		(fp_line
			(start 1.524 0.762)
			(end 1.524 -0.762)
			(stroke
				(width 0.1524)
				(type default)
			)
			(layer "B.SilkS")
		)
		(fp_line
			(start -1.524 -0.762)
			(end -1.524 0.762)
			(stroke
				(width 0.1524)
				(type default)
			)
			(layer "B.SilkS")
		)
		(fp_line
			(start 1.524 -0.762)
			(end -1.524 -0.762)
			(stroke
				(width 0.1524)
				(type default)
			)
			(layer "B.SilkS")
		)
		(fp_line
			(start -1.1049 0.724916)
			(end -1.1049 -0.724916)
			(stroke
				(width 0.1)
				(type default)
			)
			(layer "B.Fab")
		)
		(fp_line
			(start 1.1049 0.724916)
			(end -1.1049 0.724916)
			(stroke
				(width 0.1)
				(type default)
			)
			(layer "B.Fab")
		)
		(fp_line
			(start -1.1049 -0.724916)
			(end 1.1049 -0.724916)
			(stroke
				(width 0.1)
				(type default)
			)
			(layer "B.Fab")
		)
		(fp_line
			(start 1.1049 -0.724916)
			(end 1.1049 0.724916)
			(stroke
				(width 0.1)
				(type default)
			)
			(layer "B.Fab")
		)
		(pad "1" smd rect
			(at 0.889 0 270)
			(size 1.016 1.27)
			(layers "B.Cu" "B.Mask" "B.Paste")
			(net "P12V_S3_AUX_CPU1_NVDIMM")
		)
		(pad "2" smd rect
			(at -0.889 0 270)
			(size 1.016 1.27)
			(layers "B.Cu" "B.Mask" "B.Paste")
			(net "GND")
		)
	)
	(footprint ""
		(layer "B.Cu")
		(at 423.338244 -193.353436 -90)
		(property "Reference" "R842"
			(at 0 0 90)
			(layer "B.SilkS")
			(hide yes)
			(effects
				(font
					(size 1.27 1.27)
				)
				(justify mirror)
			)
		)
		(property "Value" ""
			(at 0 0 90)
			(layer "B.Fab")
			(effects
				(font
					(size 1.27 1.27)
				)
				(justify mirror)
			)
		)
		(duplicate_pad_numbers_are_jumpers no)
		(fp_line
			(start -0.7874 0.4064)
			(end 0.7874 0.4064)
			(stroke
				(width 0.1524)
				(type default)
			)
			(layer "B.SilkS")
		)
		(fp_line
			(start 0.7874 0.4064)
			(end 0.7874 -0.4064)
			(stroke
				(width 0.1524)
				(type default)
			)
			(layer "B.SilkS")
		)
		(fp_line
			(start -0.7874 -0.4064)
			(end -0.7874 0.4064)
			(stroke
				(width 0.1524)
				(type default)
			)
			(layer "B.SilkS")
		)
		(fp_line
			(start 0.7874 -0.4064)
			(end -0.7874 -0.4064)
			(stroke
				(width 0.1524)
				(type default)
			)
			(layer "B.SilkS")
		)
		(fp_line
			(start -0.67945 0.3048)
			(end -0.120396 0.3048)
			(stroke
				(width 0.1)
				(type default)
			)
			(layer "B.Fab")
		)
		(fp_line
			(start -0.120396 0.3048)
			(end -0.120396 0.2794)
			(stroke
				(width 0.1)
				(type default)
			)
			(layer "B.Fab")
		)
		(fp_line
			(start 0.12065 0.3048)
			(end 0.67945 0.3048)
			(stroke
				(width 0.1)
				(type default)
			)
			(layer "B.Fab")
		)
		(fp_line
			(start 0.67945 0.3048)
			(end 0.67945 -0.305054)
			(stroke
				(width 0.1)
				(type default)
			)
			(layer "B.Fab")
		)
		(fp_line
			(start -0.120396 0.2794)
			(end 0.12065 0.2794)
			(stroke
				(width 0.1)
				(type default)
			)
			(layer "B.Fab")
		)
		(fp_line
			(start 0.12065 0.2794)
			(end 0.12065 0.3048)
			(stroke
				(width 0.1)
				(type default)
			)
			(layer "B.Fab")
		)
		(fp_line
			(start -0.12065 -0.2794)
			(end -0.12065 -0.3048)
			(stroke
				(width 0.1)
				(type default)
			)
			(layer "B.Fab")
		)
		(fp_line
			(start 0.12065 -0.2794)
			(end -0.12065 -0.2794)
			(stroke
				(width 0.1)
				(type default)
			)
			(layer "B.Fab")
		)
		(fp_line
			(start -0.67945 -0.3048)
			(end -0.67945 0.3048)
			(stroke
				(width 0.1)
				(type default)
			)
			(layer "B.Fab")
		)
		(fp_line
			(start -0.12065 -0.3048)
			(end -0.67945 -0.3048)
			(stroke
				(width 0.1)
				(type default)
			)
			(layer "B.Fab")
		)
		(fp_line
			(start 0.12065 -0.305054)
			(end 0.12065 -0.2794)
			(stroke
				(width 0.1)
				(type default)
			)
			(layer "B.Fab")
		)
		(fp_line
			(start 0.67945 -0.305054)
			(end 0.12065 -0.305054)
			(stroke
				(width 0.1)
				(type default)
			)
			(layer "B.Fab")
		)
		(pad "1" smd circle
			(at 0.40005 0 90)
			(size 0 0)
			(layers "B.Cu" "B.Mask" "B.Paste")
			(net "PVCCD_HV_CPU0")
		)
		(pad "2" smd circle
			(at -0.40005 0 90)
			(size 0 0)
			(layers "B.Cu" "B.Mask" "B.Paste")
			(net "RST_M_EF_CPU0_FPGA_N")
		)
	)
)
